#ISCELL
  pure_quanta quanta_title_block_c *
  *
#ISCELL
  logical_power universal_gnd *
  page322_i10
#CELL
  pure_quanta q_cap *
  page322_i101
#ISCELL
  logical_power universal_gnd *
  page322_i102
#ISCELL
  logical_power universal_power *
  page322_i105
#CELL
  pure_quanta q_cap *
  page322_i106
#ISCELL
  logical_power universal_gnd *
  page322_i107
#ISCELL
  logical_power universal_power *
  page322_i11
#ISCELL
  logical_power universal_power *
  page322_i110
#CELL
  pure_quanta q_cap *
  page322_i111
#ISCELL
  logical_power universal_gnd *
  page322_i112
#ISCELL
  logical_power universal_power *
  page322_i115
#ISCELL
  standard offpage *
  page322_i116
#ISCELL
  standard offpage *
  page322_i117
#ISCELL
  standard offpage *
  page322_i118
#ISCELL
  standard offpage *
  page322_i119
#ISCELL
  standard offpage *
  page322_i120
#ISCELL
  standard offpage *
  page322_i121
#ISCELL
  standard offpage *
  page322_i122
#ISCELL
  standard offpage *
  page322_i123
#ISCELL
  standard offpage *
  page322_i126
#CELL
  pure_quanta q_res *
  page322_i128
#CELL
  pure_quanta q_res *
  page322_i129
#CELL
  pure_quanta q_res *
  page322_i130
#CELL
  pure_quanta q_res *
  page322_i131
#ISCELL
  logical_power universal_power *
  page322_i132
#CELL
  pure_quanta q_res *
  page322_i157
#CELL
  pure_quanta q_res *
  page322_i158
#CELL
  pure_quanta q_res *
  page322_i159
#CELL
  pure_quanta q_res *
  page322_i160
#ISCELL
  standard offpage *
  page322_i161
#ISCELL
  standard offpage *
  page322_i162
#CELL
  pure_quanta q_res *
  page322_i163
#CELL
  pure_quanta q_res *
  page322_i164
#ISCELL
  standard offpage *
  page322_i165
#ISCELL
  standard offpage *
  page322_i166
#ISCELL
  standard offpage *
  page322_i167
#ISCELL
  standard offpage *
  page322_i168
#CELL
  pure_quanta q_res *
  page322_i169
#CELL
  pure_quanta q_res *
  page322_i171
#CELL
  pure_quanta q_res *
  page322_i172
#CELL
  pure_quanta q_res *
  page322_i173
#CELL
  pure_quanta q_res *
  page322_i174
#ISCELL
  logical_power universal_power *
  page322_i175
#ISCELL
  logical_power universal_power *
  page322_i176
#CELL
  pure_quanta q_res *
  page322_i177
#ISCELL
  standard offpage *
  page322_i178
#ISCELL
  standard offpage *
  page322_i179
#ISCELL
  standard offpage *
  page322_i180
#CELL
  pure_quanta q_res *
  page322_i181
#CELL
  pure_quanta q_res *
  page322_i182
#CELL
  pure_quanta q_res *
  page322_i183
#CELL
  pure_quanta q_res *
  page322_i184
#ISCELL
  standard offpage *
  page322_i185
#ISCELL
  standard offpage *
  page322_i186
#CELL
  pure_quanta q_res *
  page322_i187
#CELL
  pure_quanta q_res *
  page322_i188
#CELL
  pure_quanta q_res *
  page322_i189
#CELL
  pure_quanta q_res *
  page322_i190
#ISCELL
  logical_power universal_gnd *
  page322_i191
#ISCELL
  logical_power universal_gnd *
  page322_i20
#CELL
  pure_quanta gtl2014pw *
  page322_i27
#ISCELL
  standard offpage *
  page322_i32
#ISCELL
  standard offpage *
  page322_i33
#ISCELL
  standard offpage *
  page322_i34
#ISCELL
  standard offpage *
  page322_i35
#CELL
  pure_quanta q_res *
  page322_i36
#CELL
  pure_quanta q_res *
  page322_i37
#CELL
  pure_quanta q_res *
  page322_i38
#CELL
  pure_quanta q_res *
  page322_i39
#CELL
  pure_quanta gtl2014pw *
  page322_i44
#ISCELL
  logical_power universal_gnd *
  page322_i49
#CELL
  pure_quanta q_res *
  page322_i52
#CELL
  pure_quanta q_res *
  page322_i53
#CELL
  pure_quanta q_res *
  page322_i54
#CELL
  pure_quanta q_res *
  page322_i55
#ISCELL
  logical_power universal_gnd *
  page322_i58
#CELL
  pure_quanta q_cap *
  page322_i59
#ISCELL
  logical_power universal_power *
  page322_i60
#ISCELL
  logical_power universal_gnd *
  page322_i61
#ISCELL
  standard offpage *
  page322_i62
#ISCELL
  standard offpage *
  page322_i63
#ISCELL
  standard offpage *
  page322_i64
#ISCELL
  standard offpage *
  page322_i65
#CELL
  pure_quanta q_res *
  page322_i66
#CELL
  pure_quanta q_res *
  page322_i67
#ISCELL
  logical_power universal_gnd *
  page322_i8
#CELL
  pure_quanta gtl2014pw *
  page322_i80
#CELL
  pure_quanta q_cap *
  page322_i83
#ISCELL
  logical_power universal_power *
  page322_i84
#ISCELL
  logical_power universal_gnd *
  page322_i89
#CELL
  pure_quanta q_cap *
  page322_i9
#CELL
  pure_quanta q_res *
  page322_i91
#CELL
  pure_quanta q_res *
  page322_i94
#ISCELL
  logical_power universal_gnd *
  page322_i96
#ISCELL
  logical_power universal_gnd *
  page322_i97
